# T6G (Grand Teton) — schematic netlist excerpt (pin names and nets, part order shuffled) for the footprints in the layout excerpt that follows; sources: Cadence DE-HDL packaged netlist, KiCad conversion of 04192023_DAF0TMB3IC0_F0TG_MB_C_brd_V02_OCP.brd

R8413  Q_RES  100K 1% CHIP  pkg 0402LF  page 137 : A = GND ; B = FM_OCP_V3_2_PWR_GOOD
C6604  Q_CAP_DIFFBUS  DIFF BUS_0.22UF 6.3V 20% X6S  pkg C0201  page 308 : \1\ = P5E_CPU0_P3_TX_BUF_C_DN<3> ; \2\ = P5E_CPU0_P3_TX_BUF_DN<3>
R1186  Q_RES  1K 1% CHIP  pkg 0402LF  page 83 : A = PVDDCR_CPU1_P0_SMB_ALERT ; B = P3V3_AUX

(kicad_pcb
	(version 20260206)
	(generator "pcbnew")
	(generator_version "10.0")
	(general
		(thickness 1.6)
		(legacy_teardrops no)
	)
	(paper "A4")
	(title_block
		(title "04192023_DAF0TMB3IC0_F0TG_MB_C_brd_V02_OCP.brd")
		(comment 1 "Grand Teton / footprints 6298-6300 of 8354")
	)
	(layers
		(0 "F.Cu" signal "TOP")
		(4 "In1.Cu" signal "GND")
		(6 "In2.Cu" signal "IN1")
		(8 "In3.Cu" signal "GND1")
		(10 "In4.Cu" signal "IN2")
		(12 "In5.Cu" signal "GND2")
		(14 "In6.Cu" signal "IN3")
		(16 "In7.Cu" signal "GND3")
		(18 "In8.Cu" signal "VCC")
		(20 "In9.Cu" signal "VCC1")
		(22 "In10.Cu" signal "GND4")
		(24 "In11.Cu" signal "IN4")
		(26 "In12.Cu" signal "GND5")
		(28 "In13.Cu" signal "IN5")
		(30 "In14.Cu" signal "GND6")
		(32 "In15.Cu" signal "IN6")
		(34 "In16.Cu" signal "GND7")
		(2 "B.Cu" signal "BOTTOM")
		(9 "F.Adhes" user "F.Adhesive")
		(11 "B.Adhes" user "B.Adhesive")
		(13 "F.Paste" user "Package Geometry/Pastemask Top")
		(15 "B.Paste" user "Package Geometry/Pastemask Bottom")
		(5 "F.SilkS" user "Ref Des/Silkscreen Top")
		(7 "B.SilkS" user "Ref Des/Silkscreen Bottom")
		(1 "F.Mask" user "Board Geometry/Soldermask Top")
		(3 "B.Mask" user "Board Geometry/Soldermask Bottom")
		(17 "Dwgs.User" user "User.Drawings")
		(19 "Cmts.User" user "User.Comments")
		(21 "Eco1.User" user "User.Eco1")
		(23 "Eco2.User" user "User.Eco2")
		(25 "Edge.Cuts" user "Board Geometry/Outline")
		(27 "Margin" user)
		(31 "F.CrtYd" user "Package Geometry/Place Bound Top")
		(29 "B.CrtYd" user "Package Geometry/Place Bound Bottom")
		(35 "F.Fab" user "Ref Des/Assembly Top")
		(33 "B.Fab" user "Ref Des/Assembly Bottom")
	)
	(footprint ""
		(layer "B.Cu")
		(at 184.785 -100.294948 90)
		(property "Reference" "R1186"
			(at 0 0 90)
			(layer "B.SilkS")
			(hide yes)
			(effects
				(font
					(size 1.27 1.27)
				)
				(justify mirror)
			)
		)
		(property "Value" ""
			(at 0 0 90)
			(layer "B.Fab")
			(effects
				(font
					(size 1.27 1.27)
				)
				(justify mirror)
			)
		)
		(duplicate_pad_numbers_are_jumpers no)
		(fp_line
			(start 0.7874 -0.4064)
			(end -0.7874 -0.4064)
			(stroke
				(width 0.1524)
				(type default)
			)
			(layer "B.SilkS")
		)
		(fp_line
			(start -0.7874 -0.4064)
			(end -0.7874 0.4064)
			(stroke
				(width 0.1524)
				(type default)
			)
			(layer "B.SilkS")
		)
		(fp_line
			(start 0.7874 0.4064)
			(end 0.7874 -0.4064)
			(stroke
				(width 0.1524)
				(type default)
			)
			(layer "B.SilkS")
		)
		(fp_line
			(start -0.7874 0.4064)
			(end 0.7874 0.4064)
			(stroke
				(width 0.1524)
				(type default)
			)
			(layer "B.SilkS")
		)
		(fp_line
			(start 0.67945 -0.305054)
			(end 0.12065 -0.305054)
			(stroke
				(width 0.1)
				(type default)
			)
			(layer "B.Fab")
		)
		(fp_line
			(start 0.12065 -0.305054)
			(end 0.12065 -0.2794)
			(stroke
				(width 0.1)
				(type default)
			)
			(layer "B.Fab")
		)
		(fp_line
			(start -0.12065 -0.3048)
			(end -0.67945 -0.3048)
			(stroke
				(width 0.1)
				(type default)
			)
			(layer "B.Fab")
		)
		(fp_line
			(start -0.67945 -0.3048)
			(end -0.67945 0.3048)
			(stroke
				(width 0.1)
				(type default)
			)
			(layer "B.Fab")
		)
		(fp_line
			(start 0.12065 -0.2794)
			(end -0.12065 -0.2794)
			(stroke
				(width 0.1)
				(type default)
			)
			(layer "B.Fab")
		)
		(fp_line
			(start -0.12065 -0.2794)
			(end -0.12065 -0.3048)
			(stroke
				(width 0.1)
				(type default)
			)
			(layer "B.Fab")
		)
		(fp_line
			(start 0.12065 0.2794)
			(end 0.12065 0.3048)
			(stroke
				(width 0.1)
				(type default)
			)
			(layer "B.Fab")
		)
		(fp_line
			(start -0.120396 0.2794)
			(end 0.12065 0.2794)
			(stroke
				(width 0.1)
				(type default)
			)
			(layer "B.Fab")
		)
		(fp_line
			(start 0.67945 0.3048)
			(end 0.67945 -0.305054)
			(stroke
				(width 0.1)
				(type default)
			)
			(layer "B.Fab")
		)
		(fp_line
			(start 0.12065 0.3048)
			(end 0.67945 0.3048)
			(stroke
				(width 0.1)
				(type default)
			)
			(layer "B.Fab")
		)
		(fp_line
			(start -0.120396 0.3048)
			(end -0.120396 0.2794)
			(stroke
				(width 0.1)
				(type default)
			)
			(layer "B.Fab")
		)
		(fp_line
			(start -0.67945 0.3048)
			(end -0.120396 0.3048)
			(stroke
				(width 0.1)
				(type default)
			)
			(layer "B.Fab")
		)
		(pad "1" smd circle
			(at 0.40005 0 270)
			(size 0 0)
			(layers "B.Cu" "B.Mask" "B.Paste")
			(net "PVDDCR_CPU1_P0_SMB_ALERT")
		)
		(pad "2" smd circle
			(at -0.40005 0 270)
			(size 0 0)
			(layers "B.Cu" "B.Mask" "B.Paste")
			(net "P3V3_AUX")
		)
	)
	(footprint ""
		(layer "B.Cu")
		(at 381.590042 -416.899344 90)
		(property "Reference" "C6604"
			(at 0 0 90)
			(layer "B.SilkS")
			(hide yes)
			(effects
				(font
					(size 1.27 1.27)
				)
				(justify mirror)
			)
		)
		(property "Value" ""
			(at 0 0 90)
			(layer "B.Fab")
			(effects
				(font
					(size 1.27 1.27)
				)
				(justify mirror)
			)
		)
		(duplicate_pad_numbers_are_jumpers no)
		(fp_line
			(start 0.299974 -0.150114)
			(end -0.299974 -0.150114)
			(stroke
				(width 0.1)
				(type default)
			)
			(layer "B.Fab")
		)
		(fp_line
			(start -0.299974 -0.150114)
			(end -0.299974 0.150114)
			(stroke
				(width 0.1)
				(type default)
			)
			(layer "B.Fab")
		)
		(fp_line
			(start 0.299974 0.150114)
			(end 0.299974 -0.150114)
			(stroke
				(width 0.1)
				(type default)
			)
			(layer "B.Fab")
		)
		(fp_line
			(start -0.299974 0.150114)
			(end 0.299974 0.150114)
			(stroke
				(width 0.1)
				(type default)
			)
			(layer "B.Fab")
		)
		(pad "1" smd rect
			(at 0.2667 0 270)
			(size 0.3048 0.381)
			(layers "B.Cu" "B.Mask" "B.Paste")
			(net "P5E_CPU0_P3_TX_BUF_C_DN<3>")
		)
		(pad "2" smd rect
			(at -0.2667 0 270)
			(size 0.3048 0.381)
			(layers "B.Cu" "B.Mask" "B.Paste")
			(net "P5E_CPU0_P3_TX_BUF_DN<3>")
		)
	)
	(footprint ""
		(layer "B.Cu")
		(at 79.175864 -11.26871 -90)
		(property "Reference" "R8413"
			(at 0 0 90)
			(layer "B.SilkS")
			(hide yes)
			(effects
				(font
					(size 1.27 1.27)
				)
				(justify mirror)
			)
		)
		(property "Value" ""
			(at 0 0 90)
			(layer "B.Fab")
			(effects
				(font
					(size 1.27 1.27)
				)
				(justify mirror)
			)
		)
		(duplicate_pad_numbers_are_jumpers no)
		(fp_line
			(start -0.7874 0.4064)
			(end 0.7874 0.4064)
			(stroke
				(width 0.1524)
				(type default)
			)
			(layer "B.SilkS")
		)
		(fp_line
			(start 0.7874 0.4064)
			(end 0.7874 -0.4064)
			(stroke
				(width 0.1524)
				(type default)
			)
			(layer "B.SilkS")
		)
		(fp_line
			(start -0.7874 -0.4064)
			(end -0.7874 0.4064)
			(stroke
				(width 0.1524)
				(type default)
			)
			(layer "B.SilkS")
		)
		(fp_line
			(start 0.7874 -0.4064)
			(end -0.7874 -0.4064)
			(stroke
				(width 0.1524)
				(type default)
			)
			(layer "B.SilkS")
		)
		(fp_line
			(start -0.67945 0.3048)
			(end -0.120396 0.3048)
			(stroke
				(width 0.1)
				(type default)
			)
			(layer "B.Fab")
		)
		(fp_line
			(start -0.120396 0.3048)
			(end -0.120396 0.2794)
			(stroke
				(width 0.1)
				(type default)
			)
			(layer "B.Fab")
		)
		(fp_line
			(start 0.12065 0.3048)
			(end 0.67945 0.3048)
			(stroke
				(width 0.1)
				(type default)
			)
			(layer "B.Fab")
		)
		(fp_line
			(start 0.67945 0.3048)
			(end 0.67945 -0.305054)
			(stroke
				(width 0.1)
				(type default)
			)
			(layer "B.Fab")
		)
		(fp_line
			(start -0.120396 0.2794)
			(end 0.12065 0.2794)
			(stroke
				(width 0.1)
				(type default)
			)
			(layer "B.Fab")
		)
		(fp_line
			(start 0.12065 0.2794)
			(end 0.12065 0.3048)
			(stroke
				(width 0.1)
				(type default)
			)
			(layer "B.Fab")
		)
		(fp_line
			(start -0.12065 -0.2794)
			(end -0.12065 -0.3048)
			(stroke
				(width 0.1)
				(type default)
			)
			(layer "B.Fab")
		)
		(fp_line
			(start 0.12065 -0.2794)
			(end -0.12065 -0.2794)
			(stroke
				(width 0.1)
				(type default)
			)
			(layer "B.Fab")
		)
		(fp_line
			(start -0.67945 -0.3048)
			(end -0.67945 0.3048)
			(stroke
				(width 0.1)
				(type default)
			)
			(layer "B.Fab")
		)
		(fp_line
			(start -0.12065 -0.3048)
			(end -0.67945 -0.3048)
			(stroke
				(width 0.1)
				(type default)
			)
			(layer "B.Fab")
		)
		(fp_line
			(start 0.12065 -0.305054)
			(end 0.12065 -0.2794)
			(stroke
				(width 0.1)
				(type default)
			)
			(layer "B.Fab")
		)
		(fp_line
			(start 0.67945 -0.305054)
			(end 0.12065 -0.305054)
			(stroke
				(width 0.1)
				(type default)
			)
			(layer "B.Fab")
		)
		(pad "1" smd circle
			(at 0.40005 0 90)
			(size 0 0)
			(layers "B.Cu" "B.Mask" "B.Paste")
			(net "GND")
		)
		(pad "2" smd circle
			(at -0.40005 0 90)
			(size 0 0)
			(layers "B.Cu" "B.Mask" "B.Paste")
			(net "FM_OCP_V3_2_PWR_GOOD")
		)
	)
)
